# T6G (Grand Teton) — schematic netlist excerpt (pin names and nets, part order shuffled) for the footprints in the layout excerpt that follows; sources: Cadence DE-HDL packaged netlist, KiCad conversion of 04192023_DAF0TMB3IC0_F0TG_MB_C_brd_V02_OCP.brd

C1049  Q_CAP  10UF 6.3V 20% X6S  pkg C0402  page 312 : A = P0V9_CPU0_RT3_2A ; B = GND
PC10  Q_CAP  0.1UF 25V 10% X7R  pkg 0402  page 210 : A = PVDDCR_CPU0_P1_VCC ; B = GND
C573  Q_CAP  1UF 4V 20% X6S  pkg 0201  page 279 : A = P0V9_CPU0_RT0_2A ; B = GND

(kicad_pcb
	(version 20260206)
	(generator "pcbnew")
	(generator_version "10.0")
	(general
		(thickness 1.6)
		(legacy_teardrops no)
	)
	(paper "A4")
	(title_block
		(title "04192023_DAF0TMB3IC0_F0TG_MB_C_brd_V02_OCP.brd")
		(comment 1 "Grand Teton / footprints 6441-6443 of 8354")
	)
	(layers
		(0 "F.Cu" signal "TOP")
		(4 "In1.Cu" signal "GND")
		(6 "In2.Cu" signal "IN1")
		(8 "In3.Cu" signal "GND1")
		(10 "In4.Cu" signal "IN2")
		(12 "In5.Cu" signal "GND2")
		(14 "In6.Cu" signal "IN3")
		(16 "In7.Cu" signal "GND3")
		(18 "In8.Cu" signal "VCC")
		(20 "In9.Cu" signal "VCC1")
		(22 "In10.Cu" signal "GND4")
		(24 "In11.Cu" signal "IN4")
		(26 "In12.Cu" signal "GND5")
		(28 "In13.Cu" signal "IN5")
		(30 "In14.Cu" signal "GND6")
		(32 "In15.Cu" signal "IN6")
		(34 "In16.Cu" signal "GND7")
		(2 "B.Cu" signal "BOTTOM")
		(9 "F.Adhes" user "F.Adhesive")
		(11 "B.Adhes" user "B.Adhesive")
		(13 "F.Paste" user "Package Geometry/Pastemask Top")
		(15 "B.Paste" user "Package Geometry/Pastemask Bottom")
		(5 "F.SilkS" user "Ref Des/Silkscreen Top")
		(7 "B.SilkS" user "Ref Des/Silkscreen Bottom")
		(1 "F.Mask" user "Board Geometry/Soldermask Top")
		(3 "B.Mask" user "Board Geometry/Soldermask Bottom")
		(17 "Dwgs.User" user "User.Drawings")
		(19 "Cmts.User" user "User.Comments")
		(21 "Eco1.User" user "User.Eco1")
		(23 "Eco2.User" user "User.Eco2")
		(25 "Edge.Cuts" user "Board Geometry/Outline")
		(27 "Margin" user)
		(31 "F.CrtYd" user "Package Geometry/Place Bound Top")
		(29 "B.CrtYd" user "Package Geometry/Place Bound Bottom")
		(35 "F.Fab" user "Ref Des/Assembly Top")
		(33 "B.Fab" user "Ref Des/Assembly Bottom")
	)
	(footprint ""
		(layer "B.Cu")
		(at 320.17843 -395.148562 90)
		(property "Reference" "C573"
			(at 0 0 90)
			(layer "B.SilkS")
			(hide yes)
			(effects
				(font
					(size 1.27 1.27)
				)
				(justify mirror)
			)
		)
		(property "Value" ""
			(at 0 0 90)
			(layer "B.Fab")
			(effects
				(font
					(size 1.27 1.27)
				)
				(justify mirror)
			)
		)
		(duplicate_pad_numbers_are_jumpers no)
		(fp_line
			(start 0.299974 -0.150114)
			(end -0.299974 -0.150114)
			(stroke
				(width 0.1)
				(type default)
			)
			(layer "B.Fab")
		)
		(fp_line
			(start -0.299974 -0.150114)
			(end -0.299974 0.150114)
			(stroke
				(width 0.1)
				(type default)
			)
			(layer "B.Fab")
		)
		(fp_line
			(start 0.299974 0.150114)
			(end 0.299974 -0.150114)
			(stroke
				(width 0.1)
				(type default)
			)
			(layer "B.Fab")
		)
		(fp_line
			(start -0.299974 0.150114)
			(end 0.299974 0.150114)
			(stroke
				(width 0.1)
				(type default)
			)
			(layer "B.Fab")
		)
		(pad "1" smd rect
			(at 0.2667 0 270)
			(size 0.3048 0.381)
			(layers "B.Cu" "B.Mask" "B.Paste")
			(net "P0V9_CPU0_RT0_2A")
		)
		(pad "2" smd rect
			(at -0.2667 0 270)
			(size 0.3048 0.381)
			(layers "B.Cu" "B.Mask" "B.Paste")
			(net "GND")
		)
	)
	(footprint ""
		(layer "B.Cu")
		(at 100.496878 -139.93241 90)
		(property "Reference" "PC10"
			(at 0 0 90)
			(layer "B.SilkS")
			(hide yes)
			(effects
				(font
					(size 1.27 1.27)
				)
				(justify mirror)
			)
		)
		(property "Value" ""
			(at 0 0 90)
			(layer "B.Fab")
			(effects
				(font
					(size 1.27 1.27)
				)
				(justify mirror)
			)
		)
		(duplicate_pad_numbers_are_jumpers no)
		(fp_line
			(start 0.7874 -0.4064)
			(end -0.7874 -0.4064)
			(stroke
				(width 0.1524)
				(type default)
			)
			(layer "B.SilkS")
		)
		(fp_line
			(start -0.7874 -0.4064)
			(end -0.7874 0.4064)
			(stroke
				(width 0.1524)
				(type default)
			)
			(layer "B.SilkS")
		)
		(fp_line
			(start 0.7874 0.4064)
			(end 0.7874 -0.4064)
			(stroke
				(width 0.1524)
				(type default)
			)
			(layer "B.SilkS")
		)
		(fp_line
			(start -0.7874 0.4064)
			(end 0.7874 0.4064)
			(stroke
				(width 0.1524)
				(type default)
			)
			(layer "B.SilkS")
		)
		(fp_line
			(start 0.67945 -0.305054)
			(end 0.12065 -0.305054)
			(stroke
				(width 0.1)
				(type default)
			)
			(layer "B.Fab")
		)
		(fp_line
			(start 0.12065 -0.305054)
			(end 0.12065 -0.2794)
			(stroke
				(width 0.1)
				(type default)
			)
			(layer "B.Fab")
		)
		(fp_line
			(start -0.12065 -0.3048)
			(end -0.67945 -0.3048)
			(stroke
				(width 0.1)
				(type default)
			)
			(layer "B.Fab")
		)
		(fp_line
			(start -0.67945 -0.3048)
			(end -0.67945 0.3048)
			(stroke
				(width 0.1)
				(type default)
			)
			(layer "B.Fab")
		)
		(fp_line
			(start 0.12065 -0.2794)
			(end -0.12065 -0.2794)
			(stroke
				(width 0.1)
				(type default)
			)
			(layer "B.Fab")
		)
		(fp_line
			(start -0.12065 -0.2794)
			(end -0.12065 -0.3048)
			(stroke
				(width 0.1)
				(type default)
			)
			(layer "B.Fab")
		)
		(fp_line
			(start 0.12065 0.2794)
			(end 0.12065 0.3048)
			(stroke
				(width 0.1)
				(type default)
			)
			(layer "B.Fab")
		)
		(fp_line
			(start -0.120396 0.2794)
			(end 0.12065 0.2794)
			(stroke
				(width 0.1)
				(type default)
			)
			(layer "B.Fab")
		)
		(fp_line
			(start 0.67945 0.3048)
			(end 0.67945 -0.305054)
			(stroke
				(width 0.1)
				(type default)
			)
			(layer "B.Fab")
		)
		(fp_line
			(start 0.12065 0.3048)
			(end 0.67945 0.3048)
			(stroke
				(width 0.1)
				(type default)
			)
			(layer "B.Fab")
		)
		(fp_line
			(start -0.120396 0.3048)
			(end -0.120396 0.2794)
			(stroke
				(width 0.1)
				(type default)
			)
			(layer "B.Fab")
		)
		(fp_line
			(start -0.67945 0.3048)
			(end -0.120396 0.3048)
			(stroke
				(width 0.1)
				(type default)
			)
			(layer "B.Fab")
		)
		(pad "1" smd circle
			(at 0.40005 0 270)
			(size 0 0)
			(layers "B.Cu" "B.Mask" "B.Paste")
			(net "PVDDCR_CPU0_P1_VCC")
		)
		(pad "2" smd circle
			(at -0.40005 0 270)
			(size 0 0)
			(layers "B.Cu" "B.Mask" "B.Paste")
			(net "GND")
		)
	)
	(footprint ""
		(layer "B.Cu")
		(at 374.0912 -398.942052 90)
		(property "Reference" "C1049"
			(at 0 0 90)
			(layer "B.SilkS")
			(hide yes)
			(effects
				(font
					(size 1.27 1.27)
				)
				(justify mirror)
			)
		)
		(property "Value" ""
			(at 0 0 90)
			(layer "B.Fab")
			(effects
				(font
					(size 1.27 1.27)
				)
				(justify mirror)
			)
		)
		(duplicate_pad_numbers_are_jumpers no)
		(fp_line
			(start 0.7874 -0.4064)
			(end -0.7874 -0.4064)
			(stroke
				(width 0.1524)
				(type default)
			)
			(layer "B.SilkS")
		)
		(fp_line
			(start -0.7874 -0.4064)
			(end -0.7874 0.4064)
			(stroke
				(width 0.1524)
				(type default)
			)
			(layer "B.SilkS")
		)
		(fp_line
			(start 0.7874 0.4064)
			(end 0.7874 -0.4064)
			(stroke
				(width 0.1524)
				(type default)
			)
			(layer "B.SilkS")
		)
		(fp_line
			(start -0.7874 0.4064)
			(end 0.7874 0.4064)
			(stroke
				(width 0.1524)
				(type default)
			)
			(layer "B.SilkS")
		)
		(fp_line
			(start 0.67945 -0.305054)
			(end 0.12065 -0.305054)
			(stroke
				(width 0.1)
				(type default)
			)
			(layer "B.Fab")
		)
		(fp_line
			(start 0.12065 -0.305054)
			(end 0.12065 -0.2794)
			(stroke
				(width 0.1)
				(type default)
			)
			(layer "B.Fab")
		)
		(fp_line
			(start -0.12065 -0.3048)
			(end -0.67945 -0.3048)
			(stroke
				(width 0.1)
				(type default)
			)
			(layer "B.Fab")
		)
		(fp_line
			(start -0.67945 -0.3048)
			(end -0.67945 0.3048)
			(stroke
				(width 0.1)
				(type default)
			)
			(layer "B.Fab")
		)
		(fp_line
			(start 0.12065 -0.2794)
			(end -0.12065 -0.2794)
			(stroke
				(width 0.1)
				(type default)
			)
			(layer "B.Fab")
		)
		(fp_line
			(start -0.12065 -0.2794)
			(end -0.12065 -0.3048)
			(stroke
				(width 0.1)
				(type default)
			)
			(layer "B.Fab")
		)
		(fp_line
			(start 0.12065 0.2794)
			(end 0.12065 0.3048)
			(stroke
				(width 0.1)
				(type default)
			)
			(layer "B.Fab")
		)
		(fp_line
			(start -0.120396 0.2794)
			(end 0.12065 0.2794)
			(stroke
				(width 0.1)
				(type default)
			)
			(layer "B.Fab")
		)
		(fp_line
			(start 0.67945 0.3048)
			(end 0.67945 -0.305054)
			(stroke
				(width 0.1)
				(type default)
			)
			(layer "B.Fab")
		)
		(fp_line
			(start 0.12065 0.3048)
			(end 0.67945 0.3048)
			(stroke
				(width 0.1)
				(type default)
			)
			(layer "B.Fab")
		)
		(fp_line
			(start -0.120396 0.3048)
			(end -0.120396 0.2794)
			(stroke
				(width 0.1)
				(type default)
			)
			(layer "B.Fab")
		)
		(fp_line
			(start -0.67945 0.3048)
			(end -0.120396 0.3048)
			(stroke
				(width 0.1)
				(type default)
			)
			(layer "B.Fab")
		)
		(pad "1" smd circle
			(at 0.40005 0 270)
			(size 0 0)
			(layers "B.Cu" "B.Mask" "B.Paste")
			(net "P0V9_CPU0_RT3_2A")
		)
		(pad "2" smd circle
			(at -0.40005 0 270)
			(size 0 0)
			(layers "B.Cu" "B.Mask" "B.Paste")
			(net "GND")
		)
	)
)
